G04 ================== begin FILE IDENTIFICATION RECORD ==================*
G04 Layout Name:  15669-1.brd*
G04 Film Name:    P_OUTLINE*
G04 File Format:  Gerber RS274X*
G04 File Origin:  Cadence Allegro 16.5-S056*
G04 Origin Date:  Wed Nov 16 04:07:47 2016*
G04 *
G04 Layer:  BOARD GEOMETRY/PANEL_OUTLINE*
G04 *
G04 Offset:    (0.00 0.00)*
G04 Mirror:    No*
G04 Mode:      Positive*
G04 Rotation:  0*
G04 FullContactRelief:  No*
G04 UndefLineWidth:     6.00*
G04 ================== end FILE IDENTIFICATION RECORD ====================*
%FSLAX35Y35*MOIN*%
%IR0*IPPOS*OFA0.00000B0.00000*MIA0B0*SFA1.00000B1.00000*%
%ADD10C,.006*%
G75*
%LPD*%
G75*
G54D10*
G01X-7874Y0D02*
X-75552D01*
G02X-90552Y15000I0J15000D01*
G01Y519024D01*
G02X-75552Y534024I15000J0D01*
G01X-7874D01*
G01Y1030087D02*
X-75552D01*
G03X-90552Y1015087I0J-15000D01*
G01Y1001780D01*
G03X-75552Y986780I15000J0D01*
G01X-7874D01*
G01Y1992126D02*
X-75552D01*
G03X-90552Y1977126I0J-15000D01*
G01Y1915165D01*
G03X-75552Y1900165I15000J0D01*
G01X-7874D01*
G01X1023228Y1618051D02*
Y1675945D01*
G02X1028701Y1681417I5472J0D01*
G01X1033465D01*
X1037402Y1685354D01*
Y1988189D01*
G03X1033465Y1992126I-3937J0D01*
G01X3937D01*
G03X0Y1988189I0J-3937D01*
G01Y1661189D01*
X1969Y1659220D01*
X17323D01*
G02Y1650559I0J-4331D01*
G01X1969D01*
X0Y1648591D01*
Y1243866D01*
X1969Y1241898D01*
X17323D01*
G02Y1233236I0J-4331D01*
G01X1969D01*
X0Y1231268D01*
Y747803D01*
X1969Y745835D01*
X17323D01*
G02Y737173I0J-4331D01*
G01X1969D01*
X0Y735205D01*
Y3937D01*
G03X3937Y0I3937J0D01*
G01X121260D01*
X127310Y11888D01*
G03X127953Y14567I-5263J2680D01*
G01Y17717D01*
G02X139764I5906J0D01*
G01Y14567D01*
G03X140406Y11888I5906J-1D01*
G01X146457Y0D01*
X1033465D01*
G03X1037402Y3937I0J3937D01*
G01Y1424882D01*
X1033465Y1428819D01*
X1028701D01*
G02X1023228Y1434291I0J5473D01*
G01Y1609902D01*
X1021260Y1611870D01*
X993681D01*
G02Y1616083I0J2107D01*
G01X1021260D01*
X1023228Y1618051D01*
G01X-7874Y39059D02*
G03X0I3937J0D01*
G01Y8350D02*
G03X-7874I-3937J0D01*
G01D02*
Y0D01*
G01Y251657D02*
Y39059D01*
G01X0Y251657D02*
G03X-7874I-3937J0D01*
G01Y282366D02*
G03X0I3937J0D01*
G01X-7874Y494965D02*
Y282366D01*
G01Y525673D02*
G03X0I3937J0D01*
G01Y494965D02*
G03X-7874I-3937J0D01*
G01Y534024D02*
Y525673D01*
G01X0Y993079D02*
G03X-7874I-3937J0D01*
G01Y986780D02*
Y993079D01*
G01Y1023787D02*
G03X0I3937J0D01*
G01X-7874D02*
Y1030087D01*
G01Y1930791D02*
Y1900165D01*
G01X0Y1930791D02*
G03X-7874I-3937J0D01*
G01Y1961500D02*
G03X0I3937J0D01*
G01X-7874Y1992126D02*
Y1961500D01*
G01X1045276Y0D02*
X1112953D01*
G03X1127953Y15000I0J15000D01*
G01Y493259D01*
G01X1045276Y25827D02*
G03X1037402I-3937J0D01*
G01X1045276Y0D02*
Y25827D01*
G01X1037402Y56535D02*
G03X1045276I3937J0D01*
G01D02*
Y284882D01*
G01X1037402Y315591D02*
G03X1045276I3937J0D01*
G01Y284882D02*
G03X1037402I-3937J0D01*
G01X1045276Y315591D02*
Y543937D01*
G01D02*
G03X1037402I-3937J0D01*
G01Y574646D02*
G03X1045276I3937J0D01*
G01D02*
Y802992D01*
G01X1037402Y833701D02*
G03X1045276I3937J0D01*
G01Y802992D02*
G03X1037402I-3937J0D01*
G01X1045276Y833701D02*
Y1062047D01*
G01D02*
G03X1037402I-3937J0D01*
G01Y1092756D02*
G03X1045276I3937J0D01*
G01D02*
Y1321102D01*
G01D02*
G03X1037402I-3937J0D01*
G01Y1351811D02*
G03X1045276I3937J0D01*
G01D02*
Y1377638D01*
G01D02*
X1112953D01*
G02X1127953Y1362638I0J-15000D01*
G01Y501133D01*
G01X1045276Y1732598D02*
X1112953D01*
G03X1127953Y1747598I0J15000D01*
G01Y1977126D01*
G03X1112953Y1992126I-15000J0D01*
G01X1045276D01*
G01X1037402Y1767835D02*
G03X1045276I3937J0D01*
G01Y1737126D02*
G03X1037402I-3937J0D01*
G01X1045276Y1767835D02*
Y1956890D01*
G01Y1732598D02*
Y1737126D01*
G01X1037402Y1987598D02*
G03X1045276I3937J0D01*
G01Y1956890D02*
G03X1037402I-3937J0D01*
G01X1045276Y1987598D02*
Y1992126D01*
G01X1127953Y501133D02*
G03Y493259I0J-3937D01*
M02*
